# T6G (Grand Teton) — schematic netlist excerpt (pin names and nets, part order shuffled) for the footprints in the layout excerpt that follows; sources: Cadence DE-HDL packaged netlist, KiCad conversion of 04192023_DAF0TMB3IC0_F0TG_MB_C_brd_V02_OCP.brd

PPQ5  MOSFET_NCH_1D3S  PSMNR58-30YLH IC  pkg SOT1023  page 266
  \1\  = P12V_AUX
  \2\  = P12V_AUX
  \3\  = P12V_AUX
  \4\  = P12V_HSC_GATE_G1
  \5\  = P12V_MAIN_R

PR6507  Q_RES  10K 1% CHIP  pkg 0402LF  page 360 : A = P1V8_RETIMER_CPU0_FB ; B = GND

(kicad_pcb
	(version 20260206)
	(generator "pcbnew")
	(generator_version "10.0")
	(general
		(thickness 1.6)
		(legacy_teardrops no)
	)
	(paper "A4")
	(title_block
		(title "04192023_DAF0TMB3IC0_F0TG_MB_C_brd_V02_OCP.brd")
		(comment 1 "Grand Teton / footprints 2949-2950 of 8354")
	)
	(layers
		(0 "F.Cu" signal "TOP")
		(4 "In1.Cu" signal "GND")
		(6 "In2.Cu" signal "IN1")
		(8 "In3.Cu" signal "GND1")
		(10 "In4.Cu" signal "IN2")
		(12 "In5.Cu" signal "GND2")
		(14 "In6.Cu" signal "IN3")
		(16 "In7.Cu" signal "GND3")
		(18 "In8.Cu" signal "VCC")
		(20 "In9.Cu" signal "VCC1")
		(22 "In10.Cu" signal "GND4")
		(24 "In11.Cu" signal "IN4")
		(26 "In12.Cu" signal "GND5")
		(28 "In13.Cu" signal "IN5")
		(30 "In14.Cu" signal "GND6")
		(32 "In15.Cu" signal "IN6")
		(34 "In16.Cu" signal "GND7")
		(2 "B.Cu" signal "BOTTOM")
		(9 "F.Adhes" user "F.Adhesive")
		(11 "B.Adhes" user "B.Adhesive")
		(13 "F.Paste" user "Package Geometry/Pastemask Top")
		(15 "B.Paste" user "Package Geometry/Pastemask Bottom")
		(5 "F.SilkS" user "Ref Des/Silkscreen Top")
		(7 "B.SilkS" user "Ref Des/Silkscreen Bottom")
		(1 "F.Mask" user "Board Geometry/Soldermask Top")
		(3 "B.Mask" user "Board Geometry/Soldermask Bottom")
		(17 "Dwgs.User" user "User.Drawings")
		(19 "Cmts.User" user "User.Comments")
		(21 "Eco1.User" user "User.Eco1")
		(23 "Eco2.User" user "User.Eco2")
		(25 "Edge.Cuts" user "Board Geometry/Outline")
		(27 "Margin" user)
		(31 "F.CrtYd" user "Package Geometry/Place Bound Top")
		(29 "B.CrtYd" user "Package Geometry/Place Bound Bottom")
		(35 "F.Fab" user "Ref Des/Assembly Top")
		(33 "B.Fab" user "Ref Des/Assembly Bottom")
	)
	(footprint ""
		(layer "F.Cu")
		(at 239.893602 -290.341812 89.946)
		(property "Reference" "PR6507"
			(at 0 0 89.946)
			(layer "F.SilkS")
			(hide yes)
			(effects
				(font
					(size 1.27 1.27)
				)
			)
		)
		(property "Value" ""
			(at 0 0 89.946)
			(layer "F.Fab")
			(effects
				(font
					(size 1.27 1.27)
				)
			)
		)
		(duplicate_pad_numbers_are_jumpers no)
		(fp_line
			(start -0.787275 -0.40642)
			(end 0.787525 -0.40638)
			(stroke
				(width 0.1524)
				(type default)
			)
			(layer "F.SilkS")
		)
		(fp_line
			(start 0.787525 -0.40638)
			(end 0.787275 0.40642)
			(stroke
				(width 0.1524)
				(type default)
			)
			(layer "F.SilkS")
		)
		(fp_line
			(start -0.787525 0.40638)
			(end -0.787275 -0.40642)
			(stroke
				(width 0.1524)
				(type default)
			)
			(layer "F.SilkS")
		)
		(fp_line
			(start 0.787275 0.40642)
			(end -0.787525 0.40638)
			(stroke
				(width 0.1524)
				(type default)
			)
			(layer "F.SilkS")
		)
		(fp_line
			(start -0.679484 -0.305176)
			(end -0.120683 -0.30494)
			(stroke
				(width 0.1)
				(type default)
			)
			(layer "F.Fab")
		)
		(fp_line
			(start -0.120683 -0.30494)
			(end -0.120659 -0.279286)
			(stroke
				(width 0.1)
				(type default)
			)
			(layer "F.Fab")
		)
		(fp_line
			(start 0.120617 -0.304914)
			(end 0.679417 -0.304678)
			(stroke
				(width 0.1)
				(type default)
			)
			(layer "F.Fab")
		)
		(fp_line
			(start 0.679417 -0.304678)
			(end 0.679484 0.304922)
			(stroke
				(width 0.1)
				(type default)
			)
			(layer "F.Fab")
		)
		(fp_line
			(start 0.120641 -0.279514)
			(end 0.120617 -0.304914)
			(stroke
				(width 0.1)
				(type default)
			)
			(layer "F.Fab")
		)
		(fp_line
			(start -0.120659 -0.279286)
			(end 0.120641 -0.279514)
			(stroke
				(width 0.1)
				(type default)
			)
			(layer "F.Fab")
		)
		(fp_line
			(start 0.120405 0.279287)
			(end -0.120641 0.279514)
			(stroke
				(width 0.1)
				(type default)
			)
			(layer "F.Fab")
		)
		(fp_line
			(start -0.120641 0.279514)
			(end -0.120617 0.304914)
			(stroke
				(width 0.1)
				(type default)
			)
			(layer "F.Fab")
		)
		(fp_line
			(start -0.679417 0.304678)
			(end -0.679484 -0.305176)
			(stroke
				(width 0.1)
				(type default)
			)
			(layer "F.Fab")
		)
		(fp_line
			(start 0.120429 0.304687)
			(end 0.120405 0.279287)
			(stroke
				(width 0.1)
				(type default)
			)
			(layer "F.Fab")
		)
		(fp_line
			(start -0.120617 0.304914)
			(end -0.679417 0.304678)
			(stroke
				(width 0.1)
				(type default)
			)
			(layer "F.Fab")
		)
		(fp_line
			(start 0.679484 0.304922)
			(end 0.120429 0.304687)
			(stroke
				(width 0.1)
				(type default)
			)
			(layer "F.Fab")
		)
		(pad "1" smd circle
			(at -0.40005 0 89.946)
			(size 0 0)
			(layers "F.Cu" "F.Mask" "F.Paste")
			(net "P1V8_RETIMER_CPU0_FB")
		)
		(pad "2" smd circle
			(at 0.40005 0 89.946)
			(size 0 0)
			(layers "F.Cu" "F.Mask" "F.Paste")
			(net "GND")
		)
	)
	(footprint ""
		(layer "F.Cu")
		(at 253.526036 -385.27736 90)
		(property "Reference" "PPQ5"
			(at -7.496048 -2.441956 0)
			(unlocked yes)
			(layer "F.SilkS")
			(effects
				(font
					(size 0.7874 0.5842)
					(thickness 0.1524)
				)
				(justify left)
			)
		)
		(property "Value" ""
			(at 0 0 90)
			(layer "F.Fab")
			(effects
				(font
					(size 1.27 1.27)
				)
			)
		)
		(duplicate_pad_numbers_are_jumpers no)
		(fp_line
			(start 2.350008 -2.649982)
			(end 2.350008 -2.4892)
			(stroke
				(width 0.1524)
				(type default)
			)
			(layer "F.SilkS")
		)
		(fp_line
			(start -2.350008 -2.649982)
			(end 2.350008 -2.649982)
			(stroke
				(width 0.1524)
				(type default)
			)
			(layer "F.SilkS")
		)
		(fp_line
			(start -2.350008 -2.4384)
			(end -2.350008 -2.649982)
			(stroke
				(width 0.1524)
				(type default)
			)
			(layer "F.SilkS")
		)
		(fp_line
			(start 2.350008 2.4892)
			(end 2.350008 2.649982)
			(stroke
				(width 0.1524)
				(type default)
			)
			(layer "F.SilkS")
		)
		(fp_line
			(start 2.350008 2.649982)
			(end -2.350008 2.649982)
			(stroke
				(width 0.1524)
				(type default)
			)
			(layer "F.SilkS")
		)
		(fp_line
			(start -2.350008 2.649982)
			(end -2.350008 2.413)
			(stroke
				(width 0.1524)
				(type default)
			)
			(layer "F.SilkS")
		)
		(fp_poly
			(pts
				(xy -3.438144 -3.488182) (xy -2.638044 -3.491738) (xy -3.052318 -2.44856)
			)
			(stroke
				(width 0)
				(type default)
			)
			(fill yes)
			(layer "F.SilkS")
		)
		(fp_line
			(start 2.350008 -2.649982)
			(end 2.350008 2.649982)
			(stroke
				(width 0.1)
				(type default)
			)
			(layer "F.Fab")
		)
		(fp_line
			(start -2.350008 -2.649982)
			(end 2.350008 -2.649982)
			(stroke
				(width 0.1)
				(type default)
			)
			(layer "F.Fab")
		)
		(fp_line
			(start 2.350008 2.649982)
			(end -2.350008 2.649982)
			(stroke
				(width 0.1)
				(type default)
			)
			(layer "F.Fab")
		)
		(fp_line
			(start -2.350008 2.649982)
			(end -2.350008 -2.649982)
			(stroke
				(width 0.1)
				(type default)
			)
			(layer "F.Fab")
		)
		(fp_poly
			(pts
				(xy -3.717544 -1.905) (xy -4.758944 -2.3241) (xy -4.758944 -1.524)
			)
			(stroke
				(width 0)
				(type default)
			)
			(fill yes)
			(layer "F.Fab")
		)
		(pad "1" smd rect
			(at -2.999994 -1.905)
			(size 0.7112 1.1684)
			(layers "F.Cu" "F.Mask" "F.Paste")
			(net "P12V_AUX")
		)
		(pad "2" smd rect
			(at -2.999994 -0.635)
			(size 0.7112 1.1684)
			(layers "F.Cu" "F.Mask" "F.Paste")
			(net "P12V_AUX")
		)
		(pad "3" smd rect
			(at -2.999994 0.635)
			(size 0.7112 1.1684)
			(layers "F.Cu" "F.Mask" "F.Paste")
			(net "P12V_AUX")
		)
		(pad "4" smd rect
			(at -2.999994 1.905)
			(size 0.7112 1.1684)
			(layers "F.Cu" "F.Mask" "F.Paste")
			(net "P12V_HSC_GATE_G1")
		)
		(pad "5" smd circle
			(at 0.925068 0)
			(size 0 0)
			(layers "F.Cu" "F.Mask" "F.Paste")
			(net "P12V_MAIN_R")
		)
		(zone
			(layer "F.Cu")
			(hatch none 0.5)
			(connect_pads
				(clearance 0)
			)
			(min_thickness 0.25)
			(keepout
				(tracks not_allowed)
				(vias allowed)
				(pads allowed)
				(copperpour not_allowed)
				(footprints allowed)
			)
			(placement
				(enabled no)
				(sheetname "")
			)
			(fill
				(thermal_gap 0.5)
				(thermal_bridge_width 0.5)
				(island_removal_mode 0)
			)
			(polygon
				(pts
					(xy 250.884436 -383.7178) (xy 256.167636 -383.7178) (xy 256.167636 -382.92786) (xy 250.884436 -382.92786)
				)
			)
		)
	)
)
